(kicad_pcb
	(version 20260206)
	(generator "pcbnew")
	(generator_version "10.0")
	(general
		(thickness 1.6)
		(legacy_teardrops no)
	)
	(paper "A4")
	(title_block
		(title "04192023_DAF0TMB3IC0_F0TG_MB_C_brd_V02_OCP.brd")
		(comment 1 "Grand Teton / footprints 7505-7511 of 8354")
	)
	(layers
		(0 "F.Cu" signal "TOP")
		(4 "In1.Cu" signal "GND")
		(6 "In2.Cu" signal "IN1")
		(8 "In3.Cu" signal "GND1")
		(10 "In4.Cu" signal "IN2")
		(12 "In5.Cu" signal "GND2")
		(14 "In6.Cu" signal "IN3")
		(16 "In7.Cu" signal "GND3")
		(18 "In8.Cu" signal "VCC")
		(20 "In9.Cu" signal "VCC1")
		(22 "In10.Cu" signal "GND4")
		(24 "In11.Cu" signal "IN4")
		(26 "In12.Cu" signal "GND5")
		(28 "In13.Cu" signal "IN5")
		(30 "In14.Cu" signal "GND6")
		(32 "In15.Cu" signal "IN6")
		(34 "In16.Cu" signal "GND7")
		(2 "B.Cu" signal "BOTTOM")
		(9 "F.Adhes" user "F.Adhesive")
		(11 "B.Adhes" user "B.Adhesive")
		(13 "F.Paste" user "Package Geometry/Pastemask Top")
		(15 "B.Paste" user "Package Geometry/Pastemask Bottom")
		(5 "F.SilkS" user "Ref Des/Silkscreen Top")
		(7 "B.SilkS" user "Ref Des/Silkscreen Bottom")
		(1 "F.Mask" user "Board Geometry/Soldermask Top")
		(3 "B.Mask" user "Board Geometry/Soldermask Bottom")
		(17 "Dwgs.User" user "User.Drawings")
		(19 "Cmts.User" user "User.Comments")
		(21 "Eco1.User" user "User.Eco1")
		(23 "Eco2.User" user "User.Eco2")
		(25 "Edge.Cuts" user "Board Geometry/Outline")
		(27 "Margin" user)
		(31 "F.CrtYd" user "Package Geometry/Place Bound Top")
		(29 "B.CrtYd" user "Package Geometry/Place Bound Bottom")
		(35 "F.Fab" user "Ref Des/Assembly Top")
		(33 "B.Fab" user "Ref Des/Assembly Bottom")
	)
	(footprint ""
		(layer "B.Cu")
		(at 391.104628 -314.180474 90)
		(property "Reference" "R751"
			(at 0 0 90)
			(layer "B.SilkS")
			(hide yes)
			(effects
				(font
					(size 1.27 1.27)
				)
				(justify mirror)
			)
		)
		(property "Value" ""
			(at 0 0 90)
			(layer "B.Fab")
			(effects
				(font
					(size 1.27 1.27)
				)
				(justify mirror)
			)
		)
		(duplicate_pad_numbers_are_jumpers no)
		(fp_line
			(start 0.7874 -0.4064)
			(end -0.7874 -0.4064)
			(stroke
				(width 0.1524)
				(type default)
			)
			(layer "B.SilkS")
		)
		(fp_line
			(start -0.7874 -0.4064)
			(end -0.7874 0.4064)
			(stroke
				(width 0.1524)
				(type default)
			)
			(layer "B.SilkS")
		)
		(fp_line
			(start 0.7874 0.4064)
			(end 0.7874 -0.4064)
			(stroke
				(width 0.1524)
				(type default)
			)
			(layer "B.SilkS")
		)
		(fp_line
			(start -0.7874 0.4064)
			(end 0.7874 0.4064)
			(stroke
				(width 0.1524)
				(type default)
			)
			(layer "B.SilkS")
		)
		(fp_line
			(start 0.67945 -0.305054)
			(end 0.12065 -0.305054)
			(stroke
				(width 0.1)
				(type default)
			)
			(layer "B.Fab")
		)
		(fp_line
			(start 0.12065 -0.305054)
			(end 0.12065 -0.2794)
			(stroke
				(width 0.1)
				(type default)
			)
			(layer "B.Fab")
		)
		(fp_line
			(start -0.12065 -0.3048)
			(end -0.67945 -0.3048)
			(stroke
				(width 0.1)
				(type default)
			)
			(layer "B.Fab")
		)
		(fp_line
			(start -0.67945 -0.3048)
			(end -0.67945 0.3048)
			(stroke
				(width 0.1)
				(type default)
			)
			(layer "B.Fab")
		)
		(fp_line
			(start 0.12065 -0.2794)
			(end -0.12065 -0.2794)
			(stroke
				(width 0.1)
				(type default)
			)
			(layer "B.Fab")
		)
		(fp_line
			(start -0.12065 -0.2794)
			(end -0.12065 -0.3048)
			(stroke
				(width 0.1)
				(type default)
			)
			(layer "B.Fab")
		)
		(fp_line
			(start 0.12065 0.2794)
			(end 0.12065 0.3048)
			(stroke
				(width 0.1)
				(type default)
			)
			(layer "B.Fab")
		)
		(fp_line
			(start -0.120396 0.2794)
			(end 0.12065 0.2794)
			(stroke
				(width 0.1)
				(type default)
			)
			(layer "B.Fab")
		)
		(fp_line
			(start 0.67945 0.3048)
			(end 0.67945 -0.305054)
			(stroke
				(width 0.1)
				(type default)
			)
			(layer "B.Fab")
		)
		(fp_line
			(start 0.12065 0.3048)
			(end 0.67945 0.3048)
			(stroke
				(width 0.1)
				(type default)
			)
			(layer "B.Fab")
		)
		(fp_line
			(start -0.120396 0.3048)
			(end -0.120396 0.2794)
			(stroke
				(width 0.1)
				(type default)
			)
			(layer "B.Fab")
		)
		(fp_line
			(start -0.67945 0.3048)
			(end -0.120396 0.3048)
			(stroke
				(width 0.1)
				(type default)
			)
			(layer "B.Fab")
		)
		(pad "1" smd circle
			(at 0.40005 0 270)
			(size 0 0)
			(layers "B.Cu" "B.Mask" "B.Paste")
			(net "GND")
		)
		(pad "2" smd circle
			(at -0.40005 0 270)
			(size 0 0)
			(layers "B.Cu" "B.Mask" "B.Paste")
			(net "CLK_CPU0_RTCCLK")
		)
	)
	(footprint ""
		(layer "B.Cu")
		(at 106.901996 -26.952448 90)
		(property "Reference" "C6101"
			(at 0 0 90)
			(layer "B.SilkS")
			(hide yes)
			(effects
				(font
					(size 1.27 1.27)
				)
				(justify mirror)
			)
		)
		(property "Value" ""
			(at 0 0 90)
			(layer "B.Fab")
			(effects
				(font
					(size 1.27 1.27)
				)
				(justify mirror)
			)
		)
		(duplicate_pad_numbers_are_jumpers no)
		(fp_line
			(start 0.7874 -0.4064)
			(end -0.7874 -0.4064)
			(stroke
				(width 0.1524)
				(type default)
			)
			(layer "B.SilkS")
		)
		(fp_line
			(start -0.7874 -0.4064)
			(end -0.7874 0.4064)
			(stroke
				(width 0.1524)
				(type default)
			)
			(layer "B.SilkS")
		)
		(fp_line
			(start 0.7874 0.4064)
			(end 0.7874 -0.4064)
			(stroke
				(width 0.1524)
				(type default)
			)
			(layer "B.SilkS")
		)
		(fp_line
			(start -0.7874 0.4064)
			(end 0.7874 0.4064)
			(stroke
				(width 0.1524)
				(type default)
			)
			(layer "B.SilkS")
		)
		(fp_line
			(start 0.67945 -0.305054)
			(end 0.12065 -0.305054)
			(stroke
				(width 0.1)
				(type default)
			)
			(layer "B.Fab")
		)
		(fp_line
			(start 0.12065 -0.305054)
			(end 0.12065 -0.2794)
			(stroke
				(width 0.1)
				(type default)
			)
			(layer "B.Fab")
		)
		(fp_line
			(start -0.12065 -0.3048)
			(end -0.67945 -0.3048)
			(stroke
				(width 0.1)
				(type default)
			)
			(layer "B.Fab")
		)
		(fp_line
			(start -0.67945 -0.3048)
			(end -0.67945 0.3048)
			(stroke
				(width 0.1)
				(type default)
			)
			(layer "B.Fab")
		)
		(fp_line
			(start 0.12065 -0.2794)
			(end -0.12065 -0.2794)
			(stroke
				(width 0.1)
				(type default)
			)
			(layer "B.Fab")
		)
		(fp_line
			(start -0.12065 -0.2794)
			(end -0.12065 -0.3048)
			(stroke
				(width 0.1)
				(type default)
			)
			(layer "B.Fab")
		)
		(fp_line
			(start 0.12065 0.2794)
			(end 0.12065 0.3048)
			(stroke
				(width 0.1)
				(type default)
			)
			(layer "B.Fab")
		)
		(fp_line
			(start -0.120396 0.2794)
			(end 0.12065 0.2794)
			(stroke
				(width 0.1)
				(type default)
			)
			(layer "B.Fab")
		)
		(fp_line
			(start 0.67945 0.3048)
			(end 0.67945 -0.305054)
			(stroke
				(width 0.1)
				(type default)
			)
			(layer "B.Fab")
		)
		(fp_line
			(start 0.12065 0.3048)
			(end 0.67945 0.3048)
			(stroke
				(width 0.1)
				(type default)
			)
			(layer "B.Fab")
		)
		(fp_line
			(start -0.120396 0.3048)
			(end -0.120396 0.2794)
			(stroke
				(width 0.1)
				(type default)
			)
			(layer "B.Fab")
		)
		(fp_line
			(start -0.67945 0.3048)
			(end -0.120396 0.3048)
			(stroke
				(width 0.1)
				(type default)
			)
			(layer "B.Fab")
		)
		(pad "1" smd circle
			(at 0.40005 0 270)
			(size 0 0)
			(layers "B.Cu" "B.Mask" "B.Paste")
			(net "P3V3_AUX_CPU0_USB2_AVDD33")
		)
		(pad "2" smd circle
			(at -0.40005 0 270)
			(size 0 0)
			(layers "B.Cu" "B.Mask" "B.Paste")
			(net "GND")
		)
	)
	(footprint ""
		(layer "B.Cu")
		(at 226.366578 -289.828732)
		(property "Reference" "C109"
			(at 0 0 0)
			(layer "B.SilkS")
			(hide yes)
			(effects
				(font
					(size 1.27 1.27)
				)
				(justify mirror)
			)
		)
		(property "Value" ""
			(at 0 0 0)
			(layer "B.Fab")
			(effects
				(font
					(size 1.27 1.27)
				)
				(justify mirror)
			)
		)
		(duplicate_pad_numbers_are_jumpers no)
		(fp_line
			(start -0.7874 -0.4064)
			(end -0.7874 0.4064)
			(stroke
				(width 0.1524)
				(type default)
			)
			(layer "B.SilkS")
		)
		(fp_line
			(start -0.7874 0.4064)
			(end 0.7874 0.4064)
			(stroke
				(width 0.1524)
				(type default)
			)
			(layer "B.SilkS")
		)
		(fp_line
			(start 0.7874 -0.4064)
			(end -0.7874 -0.4064)
			(stroke
				(width 0.1524)
				(type default)
			)
			(layer "B.SilkS")
		)
		(fp_line
			(start 0.7874 0.4064)
			(end 0.7874 -0.4064)
			(stroke
				(width 0.1524)
				(type default)
			)
			(layer "B.SilkS")
		)
		(fp_line
			(start -0.67945 -0.3048)
			(end -0.67945 0.3048)
			(stroke
				(width 0.1)
				(type default)
			)
			(layer "B.Fab")
		)
		(fp_line
			(start -0.67945 0.3048)
			(end -0.120396 0.3048)
			(stroke
				(width 0.1)
				(type default)
			)
			(layer "B.Fab")
		)
		(fp_line
			(start -0.12065 -0.3048)
			(end -0.67945 -0.3048)
			(stroke
				(width 0.1)
				(type default)
			)
			(layer "B.Fab")
		)
		(fp_line
			(start -0.12065 -0.2794)
			(end -0.12065 -0.3048)
			(stroke
				(width 0.1)
				(type default)
			)
			(layer "B.Fab")
		)
		(fp_line
			(start -0.120396 0.2794)
			(end 0.12065 0.2794)
			(stroke
				(width 0.1)
				(type default)
			)
			(layer "B.Fab")
		)
		(fp_line
			(start -0.120396 0.3048)
			(end -0.120396 0.2794)
			(stroke
				(width 0.1)
				(type default)
			)
			(layer "B.Fab")
		)
		(fp_line
			(start 0.12065 -0.305054)
			(end 0.12065 -0.2794)
			(stroke
				(width 0.1)
				(type default)
			)
			(layer "B.Fab")
		)
		(fp_line
			(start 0.12065 -0.2794)
			(end -0.12065 -0.2794)
			(stroke
				(width 0.1)
				(type default)
			)
			(layer "B.Fab")
		)
		(fp_line
			(start 0.12065 0.2794)
			(end 0.12065 0.3048)
			(stroke
				(width 0.1)
				(type default)
			)
			(layer "B.Fab")
		)
		(fp_line
			(start 0.12065 0.3048)
			(end 0.67945 0.3048)
			(stroke
				(width 0.1)
				(type default)
			)
			(layer "B.Fab")
		)
		(fp_line
			(start 0.67945 -0.305054)
			(end 0.12065 -0.305054)
			(stroke
				(width 0.1)
				(type default)
			)
			(layer "B.Fab")
		)
		(fp_line
			(start 0.67945 0.3048)
			(end 0.67945 -0.305054)
			(stroke
				(width 0.1)
				(type default)
			)
			(layer "B.Fab")
		)
		(pad "1" smd circle
			(at 0.40005 0 180)
			(size 0 0)
			(layers "B.Cu" "B.Mask" "B.Paste")
			(net "FM_PWRGD_P1V8_RETIMER_CPU1")
		)
		(pad "2" smd circle
			(at -0.40005 0 180)
			(size 0 0)
			(layers "B.Cu" "B.Mask" "B.Paste")
			(net "GND")
		)
	)
	(footprint ""
		(layer "B.Cu")
		(at 161.595562 -381.11303)
		(property "Reference" "C7026"
			(at 2.78384 3.128772 0)
			(unlocked yes)
			(layer "B.SilkS")
			(effects
				(font
					(size 0.7874 0.5842)
					(thickness 0.1524)
				)
				(justify left mirror)
			)
		)
		(property "Value" ""
			(at 0 0 0)
			(layer "B.Fab")
			(effects
				(font
					(size 1.27 1.27)
				)
				(justify mirror)
			)
		)
		(duplicate_pad_numbers_are_jumpers no)
		(fp_line
			(start -4.53898 -2.15011)
			(end -4.53898 2.15011)
			(stroke
				(width 0.1524)
				(type default)
			)
			(layer "B.SilkS")
		)
		(fp_line
			(start -4.53898 2.15011)
			(end 4.53898 2.15011)
			(stroke
				(width 0.1524)
				(type default)
			)
			(layer "B.SilkS")
		)
		(fp_line
			(start 4.53898 -2.150618)
			(end 4.539742 2.152142)
			(stroke
				(width 0.1524)
				(type default)
			)
			(layer "B.SilkS")
		)
		(fp_line
			(start 4.53898 -2.15011)
			(end -4.53898 -2.15011)
			(stroke
				(width 0.1524)
				(type default)
			)
			(layer "B.SilkS")
		)
		(fp_line
			(start 4.53898 2.15011)
			(end 4.53898 -2.15011)
			(stroke
				(width 0.1524)
				(type default)
			)
			(layer "B.SilkS")
		)
		(fp_line
			(start 4.69138 -2.150618)
			(end 4.692396 2.161032)
			(stroke
				(width 0.1524)
				(type default)
			)
			(layer "B.SilkS")
		)
		(fp_line
			(start 4.83108 2.150364)
			(end 4.447794 2.149348)
			(stroke
				(width 0.1524)
				(type default)
			)
			(layer "B.SilkS")
		)
		(fp_line
			(start 4.84378 -2.150618)
			(end 4.53898 -2.150618)
			(stroke
				(width 0.1524)
				(type default)
			)
			(layer "B.SilkS")
		)
		(fp_line
			(start 4.84378 -2.150618)
			(end 4.842256 2.163064)
			(stroke
				(width 0.1524)
				(type default)
			)
			(layer "B.SilkS")
		)
		(fp_line
			(start -3.64998 -2.15011)
			(end -3.64998 2.15011)
			(stroke
				(width 0.1)
				(type default)
			)
			(layer "B.Fab")
		)
		(fp_line
			(start -3.64998 2.15011)
			(end 3.64998 2.15011)
			(stroke
				(width 0.1)
				(type default)
			)
			(layer "B.Fab")
		)
		(fp_line
			(start 3.64998 -2.15011)
			(end -3.64998 -2.15011)
			(stroke
				(width 0.1)
				(type default)
			)
			(layer "B.Fab")
		)
		(fp_line
			(start 3.64998 2.15011)
			(end 3.64998 -2.15011)
			(stroke
				(width 0.1)
				(type default)
			)
			(layer "B.Fab")
		)
		(fp_text user "-"
			(at -2.568194 2.356612 0)
			(unlocked yes)
			(layer "B.SilkS")
			(effects
				(font
					(size 1.905 1.4224)
					(thickness 0.1524)
				)
				(justify left mirror)
			)
		)
		(fp_text user "+"
			(at 6.214872 -0.337058 0)
			(unlocked yes)
			(layer "B.SilkS")
			(effects
				(font
					(size 1.905 1.4224)
					(thickness 0.1524)
				)
				(justify left mirror)
			)
		)
		(fp_text user "-"
			(at -4.313174 -0.094488 0)
			(unlocked yes)
			(layer "B.Fab")
			(effects
				(font
					(size 1.905 1.4224)
					(thickness 0.1524)
				)
				(justify left mirror)
			)
		)
		(fp_text user "+"
			(at 6.214872 -0.337058 0)
			(unlocked yes)
			(layer "B.Fab")
			(effects
				(font
					(size 1.905 1.4224)
					(thickness 0.1524)
				)
				(justify left mirror)
			)
		)
		(pad "1" smd rect
			(at 3.199892 0 180)
			(size 2.413 2.8194)
			(layers "B.Cu" "B.Mask" "B.Paste")
			(net "P0V9_CPU1_RT2_2A")
		)
		(pad "2" smd rect
			(at -3.199892 0 180)
			(size 2.413 2.8194)
			(layers "B.Cu" "B.Mask" "B.Paste")
			(net "GND")
		)
	)
	(footprint ""
		(layer "B.Cu")
		(at 91.271852 -304.325274)
		(property "Reference" "R518"
			(at 0 0 0)
			(layer "B.SilkS")
			(hide yes)
			(effects
				(font
					(size 1.27 1.27)
				)
				(justify mirror)
			)
		)
		(property "Value" ""
			(at 0 0 0)
			(layer "B.Fab")
			(effects
				(font
					(size 1.27 1.27)
				)
				(justify mirror)
			)
		)
		(duplicate_pad_numbers_are_jumpers no)
		(fp_line
			(start -0.7874 -0.4064)
			(end -0.7874 0.4064)
			(stroke
				(width 0.1524)
				(type default)
			)
			(layer "B.SilkS")
		)
		(fp_line
			(start -0.7874 0.4064)
			(end 0.7874 0.4064)
			(stroke
				(width 0.1524)
				(type default)
			)
			(layer "B.SilkS")
		)
		(fp_line
			(start 0.7874 -0.4064)
			(end -0.7874 -0.4064)
			(stroke
				(width 0.1524)
				(type default)
			)
			(layer "B.SilkS")
		)
		(fp_line
			(start 0.7874 0.4064)
			(end 0.7874 -0.4064)
			(stroke
				(width 0.1524)
				(type default)
			)
			(layer "B.SilkS")
		)
		(fp_line
			(start -0.67945 -0.3048)
			(end -0.67945 0.3048)
			(stroke
				(width 0.1)
				(type default)
			)
			(layer "B.Fab")
		)
		(fp_line
			(start -0.67945 0.3048)
			(end -0.120396 0.3048)
			(stroke
				(width 0.1)
				(type default)
			)
			(layer "B.Fab")
		)
		(fp_line
			(start -0.12065 -0.3048)
			(end -0.67945 -0.3048)
			(stroke
				(width 0.1)
				(type default)
			)
			(layer "B.Fab")
		)
		(fp_line
			(start -0.12065 -0.2794)
			(end -0.12065 -0.3048)
			(stroke
				(width 0.1)
				(type default)
			)
			(layer "B.Fab")
		)
		(fp_line
			(start -0.120396 0.2794)
			(end 0.12065 0.2794)
			(stroke
				(width 0.1)
				(type default)
			)
			(layer "B.Fab")
		)
		(fp_line
			(start -0.120396 0.3048)
			(end -0.120396 0.2794)
			(stroke
				(width 0.1)
				(type default)
			)
			(layer "B.Fab")
		)
		(fp_line
			(start 0.12065 -0.305054)
			(end 0.12065 -0.2794)
			(stroke
				(width 0.1)
				(type default)
			)
			(layer "B.Fab")
		)
		(fp_line
			(start 0.12065 -0.2794)
			(end -0.12065 -0.2794)
			(stroke
				(width 0.1)
				(type default)
			)
			(layer "B.Fab")
		)
		(fp_line
			(start 0.12065 0.2794)
			(end 0.12065 0.3048)
			(stroke
				(width 0.1)
				(type default)
			)
			(layer "B.Fab")
		)
		(fp_line
			(start 0.12065 0.3048)
			(end 0.67945 0.3048)
			(stroke
				(width 0.1)
				(type default)
			)
			(layer "B.Fab")
		)
		(fp_line
			(start 0.67945 -0.305054)
			(end 0.12065 -0.305054)
			(stroke
				(width 0.1)
				(type default)
			)
			(layer "B.Fab")
		)
		(fp_line
			(start 0.67945 0.3048)
			(end 0.67945 -0.305054)
			(stroke
				(width 0.1)
				(type default)
			)
			(layer "B.Fab")
		)
		(pad "1" smd circle
			(at 0.40005 0 180)
			(size 0 0)
			(layers "B.Cu" "B.Mask" "B.Paste")
			(net "PVDD18_S5_P1")
		)
		(pad "2" smd circle
			(at -0.40005 0 180)
			(size 0 0)
			(layers "B.Cu" "B.Mask" "B.Paste")
			(net "CPU1_SA0")
		)
	)
	(footprint ""
		(layer "B.Cu")
		(at 60.679076 -338.086954 -90)
		(property "Reference" "PC417_3"
			(at 0 0 90)
			(layer "B.SilkS")
			(hide yes)
			(effects
				(font
					(size 1.27 1.27)
				)
				(justify mirror)
			)
		)
		(property "Value" ""
			(at 0 0 90)
			(layer "B.Fab")
			(effects
				(font
					(size 1.27 1.27)
				)
				(justify mirror)
			)
		)
		(duplicate_pad_numbers_are_jumpers no)
		(fp_line
			(start -1.524 0.762)
			(end 1.524 0.762)
			(stroke
				(width 0.1524)
				(type default)
			)
			(layer "B.SilkS")
		)
		(fp_line
			(start 1.524 0.762)
			(end 1.524 -0.762)
			(stroke
				(width 0.1524)
				(type default)
			)
			(layer "B.SilkS")
		)
		(fp_line
			(start -1.524 -0.762)
			(end -1.524 0.762)
			(stroke
				(width 0.1524)
				(type default)
			)
			(layer "B.SilkS")
		)
		(fp_line
			(start 1.524 -0.762)
			(end -1.524 -0.762)
			(stroke
				(width 0.1524)
				(type default)
			)
			(layer "B.SilkS")
		)
		(fp_line
			(start -1.1049 0.724916)
			(end -1.1049 -0.724916)
			(stroke
				(width 0.1)
				(type default)
			)
			(layer "B.Fab")
		)
		(fp_line
			(start 1.1049 0.724916)
			(end -1.1049 0.724916)
			(stroke
				(width 0.1)
				(type default)
			)
			(layer "B.Fab")
		)
		(fp_line
			(start -1.1049 -0.724916)
			(end 1.1049 -0.724916)
			(stroke
				(width 0.1)
				(type default)
			)
			(layer "B.Fab")
		)
		(fp_line
			(start 1.1049 -0.724916)
			(end 1.1049 0.724916)
			(stroke
				(width 0.1)
				(type default)
			)
			(layer "B.Fab")
		)
		(pad "1" smd rect
			(at 0.889 0 270)
			(size 1.016 1.27)
			(layers "B.Cu" "B.Mask" "B.Paste")
			(net "PVDDCR_CPU1_P1")
		)
		(pad "2" smd rect
			(at -0.889 0 270)
			(size 1.016 1.27)
			(layers "B.Cu" "B.Mask" "B.Paste")
			(net "GND")
		)
	)
	(footprint ""
		(layer "B.Cu")
		(at 96.575118 -335.09712 90)
		(property "Reference" "PC427_5"
			(at 0 0 90)
			(layer "B.SilkS")
			(hide yes)
			(effects
				(font
					(size 1.27 1.27)
				)
				(justify mirror)
			)
		)
		(property "Value" ""
			(at 0 0 90)
			(layer "B.Fab")
			(effects
				(font
					(size 1.27 1.27)
				)
				(justify mirror)
			)
		)
		(duplicate_pad_numbers_are_jumpers no)
		(fp_line
			(start 1.524 -0.762)
			(end -1.524 -0.762)
			(stroke
				(width 0.1524)
				(type default)
			)
			(layer "B.SilkS")
		)
		(fp_line
			(start -1.524 -0.762)
			(end -1.524 0.762)
			(stroke
				(width 0.1524)
				(type default)
			)
			(layer "B.SilkS")
		)
		(fp_line
			(start 1.524 0.762)
			(end 1.524 -0.762)
			(stroke
				(width 0.1524)
				(type default)
			)
			(layer "B.SilkS")
		)
		(fp_line
			(start -1.524 0.762)
			(end 1.524 0.762)
			(stroke
				(width 0.1524)
				(type default)
			)
			(layer "B.SilkS")
		)
		(fp_line
			(start 1.1049 -0.724916)
			(end 1.1049 0.724916)
			(stroke
				(width 0.1)
				(type default)
			)
			(layer "B.Fab")
		)
		(fp_line
			(start -1.1049 -0.724916)
			(end 1.1049 -0.724916)
			(stroke
				(width 0.1)
				(type default)
			)
			(layer "B.Fab")
		)
		(fp_line
			(start 1.1049 0.724916)
			(end -1.1049 0.724916)
			(stroke
				(width 0.1)
				(type default)
			)
			(layer "B.Fab")
		)
		(fp_line
			(start -1.1049 0.724916)
			(end -1.1049 -0.724916)
			(stroke
				(width 0.1)
				(type default)
			)
			(layer "B.Fab")
		)
		(pad "1" smd rect
			(at 0.889 0 90)
			(size 1.016 1.27)
			(layers "B.Cu" "B.Mask" "B.Paste")
			(net "SW_P12V_AUX_PVDDCR_CPU1_P1_FLT")
		)
		(pad "2" smd rect
			(at -0.889 0 90)
			(size 1.016 1.27)
			(layers "B.Cu" "B.Mask" "B.Paste")
			(net "GND")
		)
	)
)
